(kicad_pcb
	(version 20241229)
	(generator "pcbnew")
	(generator_version "9.0")
	(general
		(thickness 1.711)
		(legacy_teardrops no)
	)
	(paper "A4")
	(title_block
		(title "Antmicro Baseboard for Jetson AGX Thor")
		(date "2026-02-18")
		(rev "1.1.0")
		(company "Antmicro Ltd")
		(comment 1 "www.antmicro.com")
		(comment 9 "footprints 1155-1159 of 1170")
	)
	(layers
		(0 "F.Cu" signal)
		(4 "In1.Cu" signal)
		(6 "In2.Cu" signal)
		(8 "In3.Cu" signal)
		(10 "In4.Cu" jumper)
		(12 "In5.Cu" signal)
		(14 "In6.Cu" signal)
		(16 "In7.Cu" signal)
		(18 "In8.Cu" signal)
		(2 "B.Cu" signal)
		(9 "F.Adhes" user "F.Adhesive")
		(11 "B.Adhes" user "B.Adhesive")
		(13 "F.Paste" user)
		(15 "B.Paste" user)
		(5 "F.SilkS" user "F.Silkscreen")
		(7 "B.SilkS" user "B.Silkscreen")
		(1 "F.Mask" user)
		(3 "B.Mask" user)
		(17 "Dwgs.User" user "User.Drawings")
		(19 "Cmts.User" user "User.Comments")
		(21 "Eco1.User" user "User.Eco1")
		(23 "Eco2.User" user "User.Eco2")
		(25 "Edge.Cuts" user)
		(27 "Margin" user)
		(31 "F.CrtYd" user "F.Courtyard")
		(29 "B.CrtYd" user "B.Courtyard")
		(35 "F.Fab" user)
		(33 "B.Fab" user)
	)
	(footprint "antmicro-footprints:SOD-523"
		(layer "B.Cu")
		(at 230.069 129.6 180)
		(property "Reference" "D48"
			(at 0.999 -0.4 0)
			(layer "B.SilkS")
			(effects
				(font
					(size 0.7 0.7)
					(thickness 0.15)
				)
				(justify left bottom mirror)
			)
		)
		(property "Value" "PESD5Z5.0F"
			(at 0 -1.499 0)
			(layer "B.Fab")
			(effects
				(font
					(size 0.7 0.7)
					(thickness 0.15)
				)
				(justify left bottom mirror)
			)
		)
		(property "Datasheet" "https://assets.nexperia.com/documents/data-sheet/PESD5Z5_0.pdf"
			(at 0 0 0)
			(layer "B.Fab")
			(hide yes)
			(effects
				(font
					(size 1.27 1.27)
					(thickness 0.15)
				)
				(justify mirror)
			)
		)
		(property "Description" "Unidirectional TVS, 30 kV,  SOD-523, 5 V, 89 pF"
			(at 0 0 0)
			(layer "B.Fab")
			(hide yes)
			(effects
				(font
					(size 1.27 1.27)
					(thickness 0.15)
				)
				(justify mirror)
			)
		)
		(property "Manufacturer" "Nexperia"
			(at 0 0 180)
			(unlocked yes)
			(layer "B.Fab")
			(hide yes)
			(effects
				(font
					(size 1 1)
					(thickness 0.15)
				)
				(justify mirror)
			)
		)
		(property "MPN" "PESD5Z5.0F"
			(at 0 0 180)
			(unlocked yes)
			(layer "B.Fab")
			(hide yes)
			(effects
				(font
					(size 1 1)
					(thickness 0.15)
				)
				(justify mirror)
			)
		)
		(property "Author" "Antmicro"
			(at 0 0 180)
			(unlocked yes)
			(layer "B.Fab")
			(hide yes)
			(effects
				(font
					(size 1 1)
					(thickness 0.15)
				)
				(justify mirror)
			)
		)
		(property "License" "Apache-2.0"
			(at 0 0 180)
			(unlocked yes)
			(layer "B.Fab")
			(hide yes)
			(effects
				(font
					(size 1 1)
					(thickness 0.15)
				)
				(justify mirror)
			)
		)
		(sheetname "/USB Hub/")
		(sheetfile "usb_hub.kicad_sch")
		(attr smd)
		(fp_line
			(start -0.35 0.5)
			(end -0.35 -0.5)
			(stroke
				(width 0.15)
				(type solid)
			)
			(layer "B.SilkS")
		)
		(fp_rect
			(start -1 0.6)
			(end 1 -0.6)
			(stroke
				(width 0.05)
				(type solid)
			)
			(fill no)
			(layer "B.CrtYd")
		)
		(fp_line
			(start 0.65 0.425)
			(end 0.65 -0.423)
			(stroke
				(width 0.15)
				(type solid)
			)
			(layer "B.Fab")
		)
		(fp_line
			(start -0.35 0.4)
			(end -0.35 -0.4)
			(stroke
				(width 0.15)
				(type solid)
			)
			(layer "B.Fab")
		)
		(fp_line
			(start -0.652 0.425)
			(end 0.65 0.425)
			(stroke
				(width 0.15)
				(type solid)
			)
			(layer "B.Fab")
		)
		(fp_line
			(start -0.652 -0.423)
			(end 0.65 -0.423)
			(stroke
				(width 0.15)
				(type solid)
			)
			(layer "B.Fab")
		)
		(fp_line
			(start -0.652 -0.423)
			(end -0.652 0.425)
			(stroke
				(width 0.15)
				(type solid)
			)
			(layer "B.Fab")
		)
		(fp_text user "Author: Antmicro"
			(at -1.276 -4.7 0)
			(layer "B.Fab")
			(effects
				(font
					(size 0.7 0.7)
					(thickness 0.15)
				)
				(justify left bottom mirror)
			)
		)
		(fp_text user "License: Apache-2.0"
			(at -1.276 -5.9 0)
			(layer "B.Fab")
			(effects
				(font
					(size 0.7 0.7)
					(thickness 0.15)
				)
				(justify left bottom mirror)
			)
		)
		(fp_text user "${REFERENCE}"
			(at -1.276 -3.499 0)
			(layer "B.Fab")
			(effects
				(font
					(size 0.7 0.7)
					(thickness 0.15)
				)
				(justify left bottom mirror)
			)
		)
		(pad "1" smd roundrect
			(at -0.701 0 180)
			(size 0.5 0.6)
			(layers "B.Cu" "B.Mask" "B.Paste")
			(roundrect_rratio 0.25)
			(net 115 "/USB Hub/USBC4_VBUS")
			(pinfunction "C")
			(pintype "passive")
		)
		(pad "2" smd roundrect
			(at 0.699 0 180)
			(size 0.5 0.6)
			(layers "B.Cu" "B.Mask" "B.Paste")
			(roundrect_rratio 0.25)
			(net 1 "GND")
			(pinfunction "A")
			(pintype "passive")
		)
	)
	(footprint "antmicro-footprints:C_0402_1005Metric"
		(layer "B.Cu")
		(at 93.680001 105.5 -90)
		(descr "Capacitor SMD 0402")
		(tags "capacitor SMD 0402")
		(property "Reference" "C324"
			(at 0.9 -0.4 90)
			(layer "B.SilkS")
			(effects
				(font
					(size 0.7 0.7)
					(thickness 0.15)
				)
				(justify left bottom mirror)
			)
		)
		(property "Value" "C_100n_0402"
			(at -1.022927 -2.155213 90)
			(layer "B.Fab")
			(effects
				(font
					(size 0.7 0.7)
					(thickness 0.15)
				)
				(justify left bottom mirror)
			)
		)
		(property "Datasheet" "https://www.murata.com/products/productdetail?partno=GRM155R61H104KE14%23"
			(at 0 0 90)
			(layer "B.Fab")
			(hide yes)
			(effects
				(font
					(size 1.27 1.27)
					(thickness 0.15)
				)
				(justify mirror)
			)
		)
		(property "Description" "SMD Multilayer Ceramic Capacitor, 0.1 µF, 50 V, 0402 [1005 Metric], ± 10%, X5R, GRM Series"
			(at 0 0 90)
			(layer "B.Fab")
			(hide yes)
			(effects
				(font
					(size 1.27 1.27)
					(thickness 0.15)
				)
				(justify mirror)
			)
		)
		(property "Manufacturer" "Murata"
			(at 0 0 90)
			(unlocked yes)
			(layer "B.Fab")
			(hide yes)
			(effects
				(font
					(size 1 1)
					(thickness 0.15)
				)
				(justify mirror)
			)
		)
		(property "MPN" "GRM155R61H104KE14D"
			(at 0 0 90)
			(unlocked yes)
			(layer "B.Fab")
			(hide yes)
			(effects
				(font
					(size 1 1)
					(thickness 0.15)
				)
				(justify mirror)
			)
		)
		(property "Val" "100n"
			(at 0 0 90)
			(unlocked yes)
			(layer "B.Fab")
			(hide yes)
			(effects
				(font
					(size 1 1)
					(thickness 0.15)
				)
				(justify mirror)
			)
		)
		(property "License" "Apache-2.0"
			(at 0 0 90)
			(unlocked yes)
			(layer "B.Fab")
			(hide yes)
			(effects
				(font
					(size 1 1)
					(thickness 0.15)
				)
				(justify mirror)
			)
		)
		(property "Author" "Antmicro"
			(at 0 0 90)
			(unlocked yes)
			(layer "B.Fab")
			(hide yes)
			(effects
				(font
					(size 1 1)
					(thickness 0.15)
				)
				(justify mirror)
			)
		)
		(property "Voltage" "50V"
			(at 0 0 90)
			(unlocked yes)
			(layer "B.Fab")
			(hide yes)
			(effects
				(font
					(size 1 1)
					(thickness 0.15)
				)
				(justify mirror)
			)
		)
		(property "Dielectric" "X5R"
			(at 0 0 90)
			(unlocked yes)
			(layer "B.Fab")
			(hide yes)
			(effects
				(font
					(size 1 1)
					(thickness 0.15)
				)
				(justify mirror)
			)
		)
		(sheetname "/SoM_IO2/")
		(sheetfile "som_io2.kicad_sch")
		(attr smd)
		(fp_poly
			(pts
				(xy -0.925 0.47) (xy 0.925 0.47) (xy 0.925 -0.47) (xy -0.925 -0.47)
			)
			(stroke
				(width 0.05)
				(type default)
			)
			(fill no)
			(layer "B.CrtYd")
		)
		(fp_line
			(start -0.494 0.25)
			(end 0.504 0.25)
			(stroke
				(width 0.15)
				(type solid)
			)
			(layer "B.Fab")
		)
		(fp_line
			(start 0.504 0.25)
			(end 0.504 -0.248)
			(stroke
				(width 0.15)
				(type solid)
			)
			(layer "B.Fab")
		)
		(fp_line
			(start -0.494 -0.248)
			(end -0.494 0.25)
			(stroke
				(width 0.15)
				(type solid)
			)
			(layer "B.Fab")
		)
		(fp_line
			(start 0.504 -0.248)
			(end -0.494 -0.248)
			(stroke
				(width 0.15)
				(type solid)
			)
			(layer "B.Fab")
		)
		(fp_text user "License: Apache-2.0"
			(at -0.939 -5.799 90)
			(layer "B.Fab")
			(effects
				(font
					(size 0.7 0.7)
					(thickness 0.15)
				)
				(justify left bottom mirror)
			)
		)
		(fp_text user "Author: Antmicro"
			(at -0.939 -3.399 90)
			(layer "B.Fab")
			(effects
				(font
					(size 0.7 0.7)
					(thickness 0.15)
				)
				(justify left bottom mirror)
			)
		)
		(fp_text user "${REFERENCE}"
			(at -0.939 -4.599 90)
			(layer "B.Fab")
			(effects
				(font
					(size 0.7 0.7)
					(thickness 0.15)
				)
				(justify left bottom mirror)
			)
		)
		(pad "1" smd roundrect
			(at -0.48 0 270)
			(size 0.59 0.64)
			(layers "B.Cu" "B.Mask" "B.Paste")
			(roundrect_rratio 0.25)
			(net 707 "/Expansion connector/DP1.TX0+")
			(pintype "passive")
		)
		(pad "2" smd roundrect
			(at 0.48 0 270)
			(size 0.59 0.64)
			(layers "B.Cu" "B.Mask" "B.Paste")
			(roundrect_rratio 0.25)
			(net 1191 "/SoM_IO2/DP1.TX0_C+")
			(pintype "passive")
		)
	)
	(footprint "antmicro-footprints:R_0402_1005Metric"
		(layer "B.Cu")
		(at 200.8 126.2 180)
		(descr "Resistor SMD 0402")
		(tags "resistor SMD 0402")
		(property "Reference" "R327"
			(at -3.76 -0.358196 0)
			(layer "B.SilkS")
			(effects
				(font
					(size 0.7 0.7)
					(thickness 0.15)
				)
				(justify left bottom mirror)
			)
		)
		(property "Value" "R_100k_0402"
			(at -1.011843 -1.772046 0)
			(layer "B.Fab")
			(effects
				(font
					(size 0.7 0.7)
					(thickness 0.15)
				)
				(justify left bottom mirror)
			)
		)
		(property "Datasheet" "https://www.bourns.com/docs/product-datasheets/cr.pdf"
			(at 0 0 0)
			(layer "B.Fab")
			(hide yes)
			(effects
				(font
					(size 1.27 1.27)
					(thickness 0.15)
				)
				(justify mirror)
			)
		)
		(property "Description" "SMD Chip Resistor, 100 kohm, ± 1%, 62.5 mW, 0402 [1005 Metric], Thick Film, General Purpose"
			(at 0 0 0)
			(layer "B.Fab")
			(hide yes)
			(effects
				(font
					(size 1.27 1.27)
					(thickness 0.15)
				)
				(justify mirror)
			)
		)
		(property "MPN" "CR0402-FX-1003GLF"
			(at 0 0 0)
			(unlocked yes)
			(layer "B.Fab")
			(hide yes)
			(effects
				(font
					(size 1 1)
					(thickness 0.15)
				)
				(justify mirror)
			)
		)
		(property "Manufacturer" "Bourns"
			(at 0 0 0)
			(unlocked yes)
			(layer "B.Fab")
			(hide yes)
			(effects
				(font
					(size 1 1)
					(thickness 0.15)
				)
				(justify mirror)
			)
		)
		(property "License" "Apache-2.0"
			(at 0 0 0)
			(unlocked yes)
			(layer "B.Fab")
			(hide yes)
			(effects
				(font
					(size 1 1)
					(thickness 0.15)
				)
				(justify mirror)
			)
		)
		(property "Author" "Antmicro"
			(at 0 0 0)
			(unlocked yes)
			(layer "B.Fab")
			(hide yes)
			(effects
				(font
					(size 1 1)
					(thickness 0.15)
				)
				(justify mirror)
			)
		)
		(property "Val" "100k"
			(at 0 0 0)
			(unlocked yes)
			(layer "B.Fab")
			(hide yes)
			(effects
				(font
					(size 1 1)
					(thickness 0.15)
				)
				(justify mirror)
			)
		)
		(property "Tolerance" "1%"
			(at 0 0 0)
			(unlocked yes)
			(layer "B.Fab")
			(hide yes)
			(effects
				(font
					(size 1 1)
					(thickness 0.15)
				)
				(justify mirror)
			)
		)
		(sheetname "/USB Hub/")
		(sheetfile "usb_hub.kicad_sch")
		(attr smd)
		(fp_poly
			(pts
				(xy -0.925 0.47) (xy -0.925 -0.47) (xy 0.925 -0.47) (xy 0.925 0.47)
			)
			(stroke
				(width 0.05)
				(type default)
			)
			(fill no)
			(layer "B.CrtYd")
		)
		(fp_poly
			(pts
				(xy -0.5 0.25) (xy -0.5 -0.25) (xy 0.5 -0.25) (xy 0.5 0.25)
			)
			(stroke
				(width 0.15)
				(type solid)
			)
			(fill no)
			(layer "B.Fab")
		)
		(fp_text user "License: Apache-2.0"
			(at -0.949999 -5.169 0)
			(layer "B.Fab")
			(effects
				(font
					(size 0.7 0.7)
					(thickness 0.15)
				)
				(justify left bottom mirror)
			)
		)
		(fp_text user "${REFERENCE}"
			(at -0.95 -3.168 0)
			(layer "B.Fab")
			(effects
				(font
					(size 0.7 0.7)
					(thickness 0.15)
				)
				(justify left bottom mirror)
			)
		)
		(fp_text user "Author: Antmicro"
			(at -0.95 -4.169 0)
			(layer "B.Fab")
			(effects
				(font
					(size 0.7 0.7)
					(thickness 0.15)
				)
				(justify left bottom mirror)
			)
		)
		(pad "1" smd roundrect
			(at -0.48 0 180)
			(size 0.59 0.64)
			(layers "B.Cu" "B.Mask" "B.Paste")
			(roundrect_rratio 0.25)
			(net 1 "GND")
			(pintype "passive")
		)
		(pad "2" smd roundrect
			(at 0.48 0 180)
			(size 0.59 0.64)
			(layers "B.Cu" "B.Mask" "B.Paste")
			(roundrect_rratio 0.25)
			(net 922 "/USB Hub/HUB_SPI_D1")
			(pintype "passive")
		)
	)
	(footprint "antmicro-footprints:R_0402_1005Metric"
		(layer "B.Cu")
		(at 68.4 65.7 -90)
		(descr "Resistor SMD 0402")
		(tags "resistor SMD 0402")
		(property "Reference" "R394"
			(at 0.9 -0.5 90)
			(layer "B.SilkS")
			(effects
				(font
					(size 0.7 0.7)
					(thickness 0.15)
				)
				(justify left bottom mirror)
			)
		)
		(property "Value" "R_2k2_0402"
			(at -1.011843 -1.772047 90)
			(layer "B.Fab")
			(effects
				(font
					(size 0.7 0.7)
					(thickness 0.15)
				)
				(justify left bottom mirror)
			)
		)
		(property "Datasheet" "https://www.bourns.com/docs/product-datasheets/cr.pdf"
			(at 0 0 90)
			(layer "B.Fab")
			(hide yes)
			(effects
				(font
					(size 1.27 1.27)
					(thickness 0.15)
				)
				(justify mirror)
			)
		)
		(property "Description" "SMD Chip Resistor, 2.2 kohm, ± 1%, 62.5 mW, 0402 [1005 Metric], Thick Film, General Purpose"
			(at 0 0 90)
			(layer "B.Fab")
			(hide yes)
			(effects
				(font
					(size 1.27 1.27)
					(thickness 0.15)
				)
				(justify mirror)
			)
		)
		(property "MPN" "CR0402-FX-2201GLF"
			(at 0 0 90)
			(unlocked yes)
			(layer "B.Fab")
			(hide yes)
			(effects
				(font
					(size 1 1)
					(thickness 0.15)
				)
				(justify mirror)
			)
		)
		(property "Manufacturer" "Bourns"
			(at 0 0 90)
			(unlocked yes)
			(layer "B.Fab")
			(hide yes)
			(effects
				(font
					(size 1 1)
					(thickness 0.15)
				)
				(justify mirror)
			)
		)
		(property "License" "Apache-2.0"
			(at 0 0 90)
			(unlocked yes)
			(layer "B.Fab")
			(hide yes)
			(effects
				(font
					(size 1 1)
					(thickness 0.15)
				)
				(justify mirror)
			)
		)
		(property "Author" "Antmicro"
			(at 0 0 90)
			(unlocked yes)
			(layer "B.Fab")
			(hide yes)
			(effects
				(font
					(size 1 1)
					(thickness 0.15)
				)
				(justify mirror)
			)
		)
		(property "Val" "2k2"
			(at 0 0 90)
			(unlocked yes)
			(layer "B.Fab")
			(hide yes)
			(effects
				(font
					(size 1 1)
					(thickness 0.15)
				)
				(justify mirror)
			)
		)
		(property "Tolerance" "1%"
			(at 0 0 90)
			(unlocked yes)
			(layer "B.Fab")
			(hide yes)
			(effects
				(font
					(size 1 1)
					(thickness 0.15)
				)
				(justify mirror)
			)
		)
		(sheetname "/CSI/")
		(sheetfile "csi.kicad_sch")
		(attr smd)
		(fp_rect
			(start -0.925 0.47)
			(end 0.925 -0.47)
			(stroke
				(width 0.05)
				(type default)
			)
			(fill no)
			(layer "B.CrtYd")
		)
		(fp_rect
			(start -0.5 0.25)
			(end 0.5 -0.25)
			(stroke
				(width 0.15)
				(type solid)
			)
			(fill no)
			(layer "B.Fab")
		)
		(fp_text user "${REFERENCE}"
			(at -0.95 -3.168 90)
			(layer "B.Fab")
			(effects
				(font
					(size 0.7 0.7)
					(thickness 0.15)
				)
				(justify left bottom mirror)
			)
		)
		(fp_text user "License: Apache-2.0"
			(at -0.95 -5.169 90)
			(layer "B.Fab")
			(effects
				(font
					(size 0.7 0.7)
					(thickness 0.15)
				)
				(justify left bottom mirror)
			)
		)
		(fp_text user "Author: Antmicro"
			(at -0.95 -4.169 90)
			(layer "B.Fab")
			(effects
				(font
					(size 0.7 0.7)
					(thickness 0.15)
				)
				(justify left bottom mirror)
			)
		)
		(pad "1" smd roundrect
			(at -0.48 0 270)
			(size 0.59 0.64)
			(layers "B.Cu" "B.Mask" "B.Paste")
			(roundrect_rratio 0.25)
			(net 990 "/CSI/CSIB_I2C_VCC")
			(pintype "passive")
		)
		(pad "2" smd roundrect
			(at 0.48 0 270)
			(size 0.59 0.64)
			(layers "B.Cu" "B.Mask" "B.Paste")
			(roundrect_rratio 0.25)
			(net 992 "/CSI/SCL_CAM3")
			(pintype "passive")
		)
	)
	(footprint "antmicro-footprints:R_0402_1005Metric"
		(layer "B.Cu")
		(at 208.726 146 180)
		(descr "Resistor SMD 0402")
		(tags "resistor SMD 0402")
		(property "Reference" "R185"
			(at -3.8 -0.5 0)
			(layer "B.SilkS")
			(effects
				(font
					(size 0.7 0.7)
					(thickness 0.15)
				)
				(justify left bottom mirror)
			)
		)
		(property "Value" "R_0R_0402"
			(at -1.011843 -1.772046 0)
			(layer "B.Fab")
			(effects
				(font
					(size 0.7 0.7)
					(thickness 0.15)
				)
				(justify left bottom mirror)
			)
		)
		(property "Datasheet" "https://industrial.panasonic.com/cdbs/www-data/pdf/RDA0000/AOA0000C301.pdf"
			(at 0 0 0)
			(layer "B.Fab")
			(hide yes)
			(effects
				(font
					(size 1.27 1.27)
					(thickness 0.15)
				)
				(justify mirror)
			)
		)
		(property "Description" "SMD Chip Resistor, Jumper, 0 ohm, 100 mW, 0402 [1005 Metric], Thick Film, General Purpose"
			(at 0 0 0)
			(layer "B.Fab")
			(hide yes)
			(effects
				(font
					(size 1.27 1.27)
					(thickness 0.15)
				)
				(justify mirror)
			)
		)
		(property "MPN" "ERJ2GE0R00X"
			(at 0 0 0)
			(unlocked yes)
			(layer "B.Fab")
			(hide yes)
			(effects
				(font
					(size 1 1)
					(thickness 0.15)
				)
				(justify mirror)
			)
		)
		(property "Manufacturer" "Panasonic"
			(at 0 0 0)
			(unlocked yes)
			(layer "B.Fab")
			(hide yes)
			(effects
				(font
					(size 1 1)
					(thickness 0.15)
				)
				(justify mirror)
			)
		)
		(property "License" "Apache-2.0"
			(at 0 0 0)
			(unlocked yes)
			(layer "B.Fab")
			(hide yes)
			(effects
				(font
					(size 1 1)
					(thickness 0.15)
				)
				(justify mirror)
			)
		)
		(property "Author" "Antmicro"
			(at 0 0 0)
			(unlocked yes)
			(layer "B.Fab")
			(hide yes)
			(effects
				(font
					(size 1 1)
					(thickness 0.15)
				)
				(justify mirror)
			)
		)
		(property "Val" "0R"
			(at 0 0 0)
			(unlocked yes)
			(layer "B.Fab")
			(hide yes)
			(effects
				(font
					(size 1 1)
					(thickness 0.15)
				)
				(justify mirror)
			)
		)
		(property "Tolerance" "~"
			(at 0 0 0)
			(unlocked yes)
			(layer "B.Fab")
			(hide yes)
			(effects
				(font
					(size 1 1)
					(thickness 0.15)
				)
				(justify mirror)
			)
		)
		(property "Current" "1A"
			(at 0 0 0)
			(unlocked yes)
			(layer "B.Fab")
			(hide yes)
			(effects
				(font
					(size 1 1)
					(thickness 0.15)
				)
				(justify mirror)
			)
		)
		(sheetname "/SFP/")
		(sheetfile "sfp.kicad_sch")
		(attr smd)
		(fp_poly
			(pts
				(xy -0.925 0.47) (xy 0.925 0.47) (xy 0.925 -0.47) (xy -0.925 -0.47)
			)
			(stroke
				(width 0.05)
				(type default)
			)
			(fill no)
			(layer "B.CrtYd")
		)
		(fp_poly
			(pts
				(xy -0.5 0.25) (xy 0.5 0.25) (xy 0.5 -0.25) (xy -0.5 -0.25)
			)
			(stroke
				(width 0.15)
				(type solid)
			)
			(fill no)
			(layer "B.Fab")
		)
		(fp_text user "${REFERENCE}"
			(at -0.95 -3.168 0)
			(layer "B.Fab")
			(effects
				(font
					(size 0.7 0.7)
					(thickness 0.15)
				)
				(justify left bottom mirror)
			)
		)
		(fp_text user "Author: Antmicro"
			(at -0.95 -4.169 0)
			(layer "B.Fab")
			(effects
				(font
					(size 0.7 0.7)
					(thickness 0.15)
				)
				(justify left bottom mirror)
			)
		)
		(fp_text user "License: Apache-2.0"
			(at -0.949999 -5.169 0)
			(layer "B.Fab")
			(effects
				(font
					(size 0.7 0.7)
					(thickness 0.15)
				)
				(justify left bottom mirror)
			)
		)
		(pad "1" smd roundrect
			(at -0.48 0 180)
			(size 0.59 0.64)
			(layers "B.Cu" "B.Mask" "B.Paste")
			(roundrect_rratio 0.25)
			(net 999 "/SFP/I2C_{SFP}.SDA")
			(pintype "passive")
		)
		(pad "2" smd roundrect
			(at 0.48 0 180)
			(size 0.59 0.64)
			(layers "B.Cu" "B.Mask" "B.Paste")
			(roundrect_rratio 0.25)
			(net 824 "/SFP/SDA_SFP")
			(pintype "passive")
		)
	)
)
